(kicad_pcb
	(version 20260206)
	(generator "pcbnew")
	(generator_version "10.0")
	(general
		(thickness 1.6)
		(legacy_teardrops no)
	)
	(paper "A4")
	(title_block
		(title "Bryce Canyon_IOM_IOC_16318-2_OCP.brd")
		(comment 1 "Bryce Canyon / footprints 1372-1379 of 1605")
	)
	(layers
		(0 "F.Cu" signal "TOP")
		(4 "In1.Cu" signal "L2GND")
		(6 "In2.Cu" signal "L3")
		(8 "In3.Cu" signal "L4VCC")
		(10 "In4.Cu" signal "L5VCC")
		(12 "In5.Cu" signal "L6")
		(14 "In6.Cu" signal "L7GND")
		(2 "B.Cu" signal "BOTTOM")
		(9 "F.Adhes" user "F.Adhesive")
		(11 "B.Adhes" user "B.Adhesive")
		(13 "F.Paste" user "Package Geometry/Pastemask Top")
		(15 "B.Paste" user "Package Geometry/Pastemask Bottom")
		(5 "F.SilkS" user "Ref Des/Silkscreen Top")
		(7 "B.SilkS" user "Ref Des/Silkscreen Bottom")
		(1 "F.Mask" user "Board Geometry/Soldermask Top")
		(3 "B.Mask" user "Board Geometry/Soldermask Bottom")
		(17 "Dwgs.User" user "User.Drawings")
		(19 "Cmts.User" user "User.Comments")
		(21 "Eco1.User" user "User.Eco1")
		(23 "Eco2.User" user "User.Eco2")
		(25 "Edge.Cuts" user "Board Geometry/Outline")
		(27 "Margin" user)
		(31 "F.CrtYd" user "Package Geometry/Place Bound Top")
		(29 "B.CrtYd" user "Package Geometry/Place Bound Bottom")
		(35 "F.Fab" user "Ref Des/Assembly Top")
		(33 "B.Fab" user "Ref Des/Assembly Bottom")
	)
	(footprint ""
		(layer "B.Cu")
		(at 195.5292 -64.8081 90)
		(property "Reference" "C402"
			(at 0 0 90)
			(layer "B.SilkS")
			(hide yes)
			(effects
				(font
					(size 1.27 1.27)
				)
				(justify mirror)
			)
		)
		(property "Value" "SCD1U6D3V1KX-GP"
			(at 2.8321 -1.7399 90)
			(unlocked yes)
			(layer "B.Fab")
			(hide yes)
			(effects
				(font
					(size 1.016 1.016)
					(thickness 0.1524)
				)
				(justify mirror)
			)
		)
		(property "Device Type" "C0201H13"
			(at 2.8321 -3.2639 90)
			(unlocked yes)
			(layer "B.Fab")
			(hide yes)
			(effects
				(font
					(size 1.016 1.016)
					(thickness 0.1524)
				)
				(justify mirror)
			)
		)
		(duplicate_pad_numbers_are_jumpers no)
		(fp_rect
			(start 0.2794 0.6477)
			(end -0.2794 -0.6477)
			(stroke
				(width 0)
				(type default)
			)
			(fill no)
			(layer "B.CrtYd")
		)
		(fp_rect
			(start 0.2794 0.6477)
			(end -0.2794 -0.6477)
			(stroke
				(width 0)
				(type default)
			)
			(fill no)
			(layer "B.Fab")
		)
		(pad "1" smd custom
			(at 0 -0.2794 270)
			(size 0.0762 0.0762)
			(layers "B.Cu" "B.Mask" "B.Paste")
			(net "P0V975")
			(options
				(clearance outline)
				(anchor circle)
			)
			(primitives
				(gr_poly
					(pts
						(arc
							(start 0.1524 0.127)
							(mid 0.137521 0.162921)
							(end 0.1016 0.1778)
						)
						(arc
							(start -0.1016 0.1778)
							(mid -0.137521 0.162921)
							(end -0.1524 0.127)
						)
						(arc
							(start -0.1524 -0.127)
							(mid -0.137521 -0.162921)
							(end -0.1016 -0.1778)
						)
						(arc
							(start 0.1016 -0.1778)
							(mid 0.137521 -0.162921)
							(end 0.1524 -0.127)
						)
					)
					(width 0)
					(fill yes)
				)
			)
		)
		(pad "2" smd custom
			(at 0 0.2794 270)
			(size 0.0762 0.0762)
			(layers "B.Cu" "B.Mask" "B.Paste")
			(net "GND")
			(options
				(clearance outline)
				(anchor circle)
			)
			(primitives
				(gr_poly
					(pts
						(arc
							(start 0.1524 0.127)
							(mid 0.137521 0.162921)
							(end 0.1016 0.1778)
						)
						(arc
							(start -0.1016 0.1778)
							(mid -0.137521 0.162921)
							(end -0.1524 0.127)
						)
						(arc
							(start -0.1524 -0.127)
							(mid -0.137521 -0.162921)
							(end -0.1016 -0.1778)
						)
						(arc
							(start 0.1016 -0.1778)
							(mid 0.137521 -0.162921)
							(end 0.1524 -0.127)
						)
					)
					(width 0)
					(fill yes)
				)
			)
		)
	)
	(footprint ""
		(layer "B.Cu")
		(at 197.5612 -51.435 -90)
		(property "Reference" "C346"
			(at 0 0 90)
			(layer "B.SilkS")
			(hide yes)
			(effects
				(font
					(size 1.27 1.27)
				)
				(justify mirror)
			)
		)
		(property "Value" "SC22U6D3V3MX-9-GP-U"
			(at 0 -2.8194 270)
			(unlocked yes)
			(layer "B.Fab")
			(hide yes)
			(effects
				(font
					(size 1.016 1.016)
					(thickness 0.1524)
				)
				(justify mirror)
			)
		)
		(property "Device Type" "C603H40"
			(at 0 -4.3434 270)
			(unlocked yes)
			(layer "B.Fab")
			(hide yes)
			(effects
				(font
					(size 1.016 1.016)
					(thickness 0.1524)
				)
				(justify mirror)
			)
		)
		(duplicate_pad_numbers_are_jumpers no)
		(fp_line
			(start -0.508 0)
			(end 0.508 0)
			(stroke
				(width 0.2032)
				(type default)
			)
			(layer "B.SilkS")
		)
		(fp_rect
			(start 0.5842 1.3335)
			(end -0.5842 -1.3335)
			(stroke
				(width 0)
				(type default)
			)
			(fill no)
			(layer "B.CrtYd")
		)
		(fp_rect
			(start 0.5842 1.3335)
			(end -0.5842 -1.3335)
			(stroke
				(width 0)
				(type default)
			)
			(fill no)
			(layer "B.Fab")
		)
		(pad "1" smd custom
			(at 0 -0.762 90)
			(size 0.2159 0.2159)
			(layers "B.Cu" "B.Mask" "B.Paste")
			(net "VDDA_SAS_REF_CLK")
			(options
				(clearance outline)
				(anchor circle)
			)
			(primitives
				(gr_poly
					(pts
						(arc
							(start -0.3302 0.4318)
							(mid -0.402042 0.402042)
							(end -0.4318 0.3302)
						)
						(arc
							(start -0.4318 -0.3302)
							(mid -0.402042 -0.402042)
							(end -0.3302 -0.4318)
						)
						(arc
							(start 0.3302 -0.4318)
							(mid 0.402042 -0.402042)
							(end 0.4318 -0.3302)
						)
						(arc
							(start 0.4318 0.3302)
							(mid 0.402042 0.402042)
							(end 0.3302 0.4318)
						)
					)
					(width 0)
					(fill yes)
				)
			)
		)
		(pad "2" smd custom
			(at 0 0.762 90)
			(size 0.2159 0.2159)
			(layers "B.Cu" "B.Mask" "B.Paste")
			(net "GND")
			(options
				(clearance outline)
				(anchor circle)
			)
			(primitives
				(gr_poly
					(pts
						(arc
							(start -0.3302 0.4318)
							(mid -0.402042 0.402042)
							(end -0.4318 0.3302)
						)
						(arc
							(start -0.4318 -0.3302)
							(mid -0.402042 -0.402042)
							(end -0.3302 -0.4318)
						)
						(arc
							(start 0.3302 -0.4318)
							(mid 0.402042 -0.402042)
							(end 0.4318 -0.3302)
						)
						(arc
							(start 0.4318 0.3302)
							(mid 0.402042 0.402042)
							(end 0.3302 0.4318)
						)
					)
					(width 0)
					(fill yes)
				)
			)
		)
	)
	(footprint ""
		(layer "B.Cu")
		(at 49.082452 -118.36019)
		(property "Reference" "TP19"
			(at 0 0 0)
			(layer "B.SilkS")
			(hide yes)
			(effects
				(font
					(size 1.27 1.27)
				)
				(justify mirror)
			)
		)
		(property "Value" "TPAD32-GP"
			(at 0.0508 -1.6764 0)
			(unlocked yes)
			(layer "B.Fab")
			(hide yes)
			(effects
				(font
					(size 1.016 1.016)
					(thickness 0.1524)
				)
				(justify mirror)
			)
		)
		(property "Device Type" "TPAD32"
			(at 0.0508 -3.2004 0)
			(unlocked yes)
			(layer "B.Fab")
			(hide yes)
			(effects
				(font
					(size 1.016 1.016)
					(thickness 0.1524)
				)
				(justify mirror)
			)
		)
		(duplicate_pad_numbers_are_jumpers no)
		(fp_poly
			(pts
				(arc
					(start 0.4064 0)
					(mid -0.4064 0)
					(end 0.4064 0)
				)
			)
			(stroke
				(width 0)
				(type default)
			)
			(fill no)
			(layer "B.CrtYd")
		)
		(fp_poly
			(pts
				(arc
					(start 0.7112 0)
					(mid -0.7112 0)
					(end 0.7112 0)
				)
			)
			(stroke
				(width 0)
				(type default)
			)
			(fill no)
			(layer "B.Fab")
		)
		(pad "1" smd circle
			(at 0 0 180)
			(size 0.8128 0.8128)
			(layers "B.Cu" "B.Mask" "B.Paste")
			(net "TEMP_3_ALERT")
		)
	)
	(footprint ""
		(layer "B.Cu")
		(at 191.5795 -68.3006 -90)
		(property "Reference" "C423"
			(at 0 0 90)
			(layer "B.SilkS")
			(hide yes)
			(effects
				(font
					(size 1.27 1.27)
				)
				(justify mirror)
			)
		)
		(property "Value" "SC1KP50V2KX-1GP"
			(at -1.1811 -2.7051 270)
			(unlocked yes)
			(layer "B.Fab")
			(hide yes)
			(effects
				(font
					(size 1.016 1.016)
					(thickness 0.1524)
				)
				(justify mirror)
			)
		)
		(property "Device Type" "C402H22"
			(at -1.1811 -4.2291 270)
			(unlocked yes)
			(layer "B.Fab")
			(hide yes)
			(effects
				(font
					(size 1.016 1.016)
					(thickness 0.1524)
				)
				(justify mirror)
			)
		)
		(duplicate_pad_numbers_are_jumpers no)
		(fp_rect
			(start 0.4318 0.9525)
			(end -0.4318 -0.9525)
			(stroke
				(width 0)
				(type default)
			)
			(fill no)
			(layer "B.CrtYd")
		)
		(fp_rect
			(start 0.4318 0.9525)
			(end -0.4318 -0.9525)
			(stroke
				(width 0)
				(type default)
			)
			(fill no)
			(layer "B.Fab")
		)
		(pad "1" smd custom
			(at 0 -0.4445 90)
			(size 0.1524 0.1524)
			(layers "B.Cu" "B.Mask" "B.Paste")
			(net "P0V975")
			(options
				(clearance outline)
				(anchor circle)
			)
			(primitives
				(gr_poly
					(pts
						(arc
							(start 0.3048 0.2032)
							(mid 0.275042 0.275042)
							(end 0.2032 0.3048)
						)
						(arc
							(start -0.2032 0.3048)
							(mid -0.275042 0.275042)
							(end -0.3048 0.2032)
						)
						(arc
							(start -0.3048 -0.2032)
							(mid -0.275042 -0.275042)
							(end -0.2032 -0.3048)
						)
						(arc
							(start 0.2032 -0.3048)
							(mid 0.275042 -0.275042)
							(end 0.3048 -0.2032)
						)
					)
					(width 0)
					(fill yes)
				)
			)
		)
		(pad "2" smd custom
			(at 0 0.4445 90)
			(size 0.1524 0.1524)
			(layers "B.Cu" "B.Mask" "B.Paste")
			(net "GND")
			(options
				(clearance outline)
				(anchor circle)
			)
			(primitives
				(gr_poly
					(pts
						(arc
							(start 0.3048 0.2032)
							(mid 0.275042 0.275042)
							(end 0.2032 0.3048)
						)
						(arc
							(start -0.2032 0.3048)
							(mid -0.275042 0.275042)
							(end -0.3048 0.2032)
						)
						(arc
							(start -0.3048 -0.2032)
							(mid -0.275042 -0.275042)
							(end -0.2032 -0.3048)
						)
						(arc
							(start 0.2032 -0.3048)
							(mid 0.275042 -0.275042)
							(end 0.3048 -0.2032)
						)
					)
					(width 0)
					(fill yes)
				)
			)
		)
	)
	(footprint ""
		(layer "B.Cu")
		(at 39.53764 -152.18156 -90)
		(property "Reference" "TP65"
			(at 0 0 90)
			(layer "B.SilkS")
			(hide yes)
			(effects
				(font
					(size 1.27 1.27)
				)
				(justify mirror)
			)
		)
		(property "Value" "TPAD28-2-GP"
			(at 0.0127 -1.6637 270)
			(unlocked yes)
			(layer "B.Fab")
			(hide yes)
			(effects
				(font
					(size 1.016 1.016)
					(thickness 0.1524)
				)
				(justify mirror)
			)
		)
		(property "Device Type" "TPAD28"
			(at 0.0127 -3.1877 270)
			(unlocked yes)
			(layer "B.Fab")
			(hide yes)
			(effects
				(font
					(size 1.016 1.016)
					(thickness 0.1524)
				)
				(justify mirror)
			)
		)
		(duplicate_pad_numbers_are_jumpers no)
		(fp_poly
			(pts
				(arc
					(start 0 -0.3556)
					(mid 0 0.3556)
					(end 0 -0.3556)
				)
			)
			(stroke
				(width 0)
				(type default)
			)
			(fill no)
			(layer "B.CrtYd")
		)
		(fp_poly
			(pts
				(arc
					(start 0 -0.6096)
					(mid 0 0.6096)
					(end 0 -0.6096)
				)
			)
			(stroke
				(width 0)
				(type default)
			)
			(fill no)
			(layer "B.Fab")
		)
		(pad "1" smd circle
			(at 0 0 90)
			(size 0.7112 0.7112)
			(layers "B.Cu" "B.Mask" "B.Paste")
			(net "TP_BMC_GPION6")
		)
	)
	(footprint ""
		(layer "B.Cu")
		(at 192.915032 -72.380856 -90)
		(property "Reference" "C367"
			(at 0 0 90)
			(layer "B.SilkS")
			(hide yes)
			(effects
				(font
					(size 1.27 1.27)
				)
				(justify mirror)
			)
		)
		(property "Value" "SCD1U6D3V1KX-GP"
			(at 2.8321 -1.7399 270)
			(unlocked yes)
			(layer "B.Fab")
			(hide yes)
			(effects
				(font
					(size 1.016 1.016)
					(thickness 0.1524)
				)
				(justify mirror)
			)
		)
		(property "Device Type" "C0201H13"
			(at 2.8321 -3.2639 270)
			(unlocked yes)
			(layer "B.Fab")
			(hide yes)
			(effects
				(font
					(size 1.016 1.016)
					(thickness 0.1524)
				)
				(justify mirror)
			)
		)
		(duplicate_pad_numbers_are_jumpers no)
		(fp_rect
			(start 0.2794 0.6477)
			(end -0.2794 -0.6477)
			(stroke
				(width 0)
				(type default)
			)
			(fill no)
			(layer "B.CrtYd")
		)
		(fp_rect
			(start 0.2794 0.6477)
			(end -0.2794 -0.6477)
			(stroke
				(width 0)
				(type default)
			)
			(fill no)
			(layer "B.Fab")
		)
		(pad "1" smd custom
			(at 0 -0.2794 90)
			(size 0.0762 0.0762)
			(layers "B.Cu" "B.Mask" "B.Paste")
			(net "PCE_AVDD")
			(options
				(clearance outline)
				(anchor circle)
			)
			(primitives
				(gr_poly
					(pts
						(arc
							(start 0.1524 0.127)
							(mid 0.137521 0.162921)
							(end 0.1016 0.1778)
						)
						(arc
							(start -0.1016 0.1778)
							(mid -0.137521 0.162921)
							(end -0.1524 0.127)
						)
						(arc
							(start -0.1524 -0.127)
							(mid -0.137521 -0.162921)
							(end -0.1016 -0.1778)
						)
						(arc
							(start 0.1016 -0.1778)
							(mid 0.137521 -0.162921)
							(end 0.1524 -0.127)
						)
					)
					(width 0)
					(fill yes)
				)
			)
		)
		(pad "2" smd custom
			(at 0 0.2794 90)
			(size 0.0762 0.0762)
			(layers "B.Cu" "B.Mask" "B.Paste")
			(net "GND")
			(options
				(clearance outline)
				(anchor circle)
			)
			(primitives
				(gr_poly
					(pts
						(arc
							(start 0.1524 0.127)
							(mid 0.137521 0.162921)
							(end 0.1016 0.1778)
						)
						(arc
							(start -0.1016 0.1778)
							(mid -0.137521 0.162921)
							(end -0.1524 0.127)
						)
						(arc
							(start -0.1524 -0.127)
							(mid -0.137521 -0.162921)
							(end -0.1016 -0.1778)
						)
						(arc
							(start 0.1016 -0.1778)
							(mid 0.137521 -0.162921)
							(end 0.1524 -0.127)
						)
					)
					(width 0)
					(fill yes)
				)
			)
		)
	)
	(footprint ""
		(layer "B.Cu")
		(at 67.771264 -142.960598)
		(property "Reference" "R161"
			(at 0 0 0)
			(layer "B.SilkS")
			(hide yes)
			(effects
				(font
					(size 1.27 1.27)
				)
				(justify mirror)
			)
		)
		(property "Value" "0R2J-2-GP"
			(at -0.064008 -3.993896 0)
			(unlocked yes)
			(layer "B.Fab")
			(hide yes)
			(effects
				(font
					(size 1.016 1.016)
					(thickness 0.1524)
				)
				(justify mirror)
			)
		)
		(property "Device Type" "R402H16"
			(at -0.064008 -5.517896 0)
			(unlocked yes)
			(layer "B.Fab")
			(hide yes)
			(effects
				(font
					(size 1.016 1.016)
					(thickness 0.1524)
				)
				(justify mirror)
			)
		)
		(duplicate_pad_numbers_are_jumpers no)
		(fp_line
			(start -0.508 -0.9398)
			(end 0.508 -0.9398)
			(stroke
				(width 0.1524)
				(type default)
			)
			(layer "B.SilkS")
		)
		(fp_line
			(start 0.508 -0.9398)
			(end 0.508 0.9398)
			(stroke
				(width 0.1524)
				(type default)
			)
			(layer "B.SilkS")
		)
		(fp_rect
			(start 0.508 0.9398)
			(end -0.508 -0.9398)
			(stroke
				(width 0)
				(type default)
			)
			(fill no)
			(layer "B.CrtYd")
		)
		(fp_rect
			(start 0.508 0.9398)
			(end -0.508 -0.9398)
			(stroke
				(width 0)
				(type default)
			)
			(fill no)
			(layer "B.Fab")
		)
		(pad "1" smd custom
			(at 0 -0.4445 180)
			(size 0.1397 0.1397)
			(layers "B.Cu" "B.Mask" "B.Paste")
			(net "BMC_SMB12_DAT")
			(options
				(clearance outline)
				(anchor circle)
			)
			(primitives
				(gr_poly
					(pts
						(arc
							(start -0.1778 0.2794)
							(mid -0.249642 0.249642)
							(end -0.2794 0.1778)
						)
						(arc
							(start -0.2794 -0.1778)
							(mid -0.249642 -0.249642)
							(end -0.1778 -0.2794)
						)
						(arc
							(start 0.1778 -0.2794)
							(mid 0.249642 -0.249642)
							(end 0.2794 -0.1778)
						)
						(arc
							(start 0.2794 0.1778)
							(mid 0.249642 0.249642)
							(end 0.1778 0.2794)
						)
					)
					(width 0)
					(fill yes)
				)
			)
		)
		(pad "2" smd custom
			(at 0 0.4445 180)
			(size 0.1397 0.1397)
			(layers "B.Cu" "B.Mask" "B.Paste")
			(net "I2C_DEBUG_SDA_L")
			(options
				(clearance outline)
				(anchor circle)
			)
			(primitives
				(gr_poly
					(pts
						(arc
							(start -0.1778 0.2794)
							(mid -0.249642 0.249642)
							(end -0.2794 0.1778)
						)
						(arc
							(start -0.2794 -0.1778)
							(mid -0.249642 -0.249642)
							(end -0.1778 -0.2794)
						)
						(arc
							(start 0.1778 -0.2794)
							(mid 0.249642 -0.249642)
							(end 0.2794 -0.1778)
						)
						(arc
							(start 0.2794 0.1778)
							(mid 0.249642 0.249642)
							(end 0.1778 0.2794)
						)
					)
					(width 0)
					(fill yes)
				)
			)
		)
	)
	(footprint ""
		(layer "B.Cu")
		(at 201.177398 -51.439572 -90)
		(property "Reference" "C334"
			(at 0 0 90)
			(layer "B.SilkS")
			(hide yes)
			(effects
				(font
					(size 1.27 1.27)
				)
				(justify mirror)
			)
		)
		(property "Value" "SC22U6D3V3MX-9-GP-U"
			(at 0 -2.8194 270)
			(unlocked yes)
			(layer "B.Fab")
			(hide yes)
			(effects
				(font
					(size 1.016 1.016)
					(thickness 0.1524)
				)
				(justify mirror)
			)
		)
		(property "Device Type" "C603H40"
			(at 0 -4.3434 270)
			(unlocked yes)
			(layer "B.Fab")
			(hide yes)
			(effects
				(font
					(size 1.016 1.016)
					(thickness 0.1524)
				)
				(justify mirror)
			)
		)
		(duplicate_pad_numbers_are_jumpers no)
		(fp_line
			(start -0.508 0)
			(end 0.508 0)
			(stroke
				(width 0.2032)
				(type default)
			)
			(layer "B.SilkS")
		)
		(fp_rect
			(start 0.5842 1.3335)
			(end -0.5842 -1.3335)
			(stroke
				(width 0)
				(type default)
			)
			(fill no)
			(layer "B.CrtYd")
		)
		(fp_rect
			(start 0.5842 1.3335)
			(end -0.5842 -1.3335)
			(stroke
				(width 0)
				(type default)
			)
			(fill no)
			(layer "B.Fab")
		)
		(pad "1" smd custom
			(at 0 -0.762 90)
			(size 0.2159 0.2159)
			(layers "B.Cu" "B.Mask" "B.Paste")
			(net "SYS_PLL_VDD")
			(options
				(clearance outline)
				(anchor circle)
			)
			(primitives
				(gr_poly
					(pts
						(arc
							(start -0.3302 0.4318)
							(mid -0.402042 0.402042)
							(end -0.4318 0.3302)
						)
						(arc
							(start -0.4318 -0.3302)
							(mid -0.402042 -0.402042)
							(end -0.3302 -0.4318)
						)
						(arc
							(start 0.3302 -0.4318)
							(mid 0.402042 -0.402042)
							(end 0.4318 -0.3302)
						)
						(arc
							(start 0.4318 0.3302)
							(mid 0.402042 0.402042)
							(end 0.3302 0.4318)
						)
					)
					(width 0)
					(fill yes)
				)
			)
		)
		(pad "2" smd custom
			(at 0 0.762 90)
			(size 0.2159 0.2159)
			(layers "B.Cu" "B.Mask" "B.Paste")
			(net "GND")
			(options
				(clearance outline)
				(anchor circle)
			)
			(primitives
				(gr_poly
					(pts
						(arc
							(start -0.3302 0.4318)
							(mid -0.402042 0.402042)
							(end -0.4318 0.3302)
						)
						(arc
							(start -0.4318 -0.3302)
							(mid -0.402042 -0.402042)
							(end -0.3302 -0.4318)
						)
						(arc
							(start 0.3302 -0.4318)
							(mid 0.402042 -0.402042)
							(end 0.4318 -0.3302)
						)
						(arc
							(start 0.4318 0.3302)
							(mid 0.402042 0.402042)
							(end 0.3302 0.4318)
						)
					)
					(width 0)
					(fill yes)
				)
			)
		)
	)
)
